(kicad_pcb
	(version 20260206)
	(generator "pcbnew")
	(generator_version "10.0")
	(general
		(thickness 1.6)
		(legacy_teardrops no)
	)
	(paper "A4")
	(title_block
		(title "Wiwynn_Tioga_Pass_MB.brd")
		(comment 1 "Tioga Pass / footprints 2630-2637 of 4770")
	)
	(layers
		(0 "F.Cu" signal "TOP")
		(4 "In1.Cu" signal "L2GND")
		(6 "In2.Cu" signal "L3")
		(8 "In3.Cu" signal "L4GND")
		(10 "In4.Cu" signal "L5")
		(12 "In5.Cu" signal "L6GND")
		(14 "In6.Cu" signal "L7VCC")
		(16 "In7.Cu" signal "L8VCC")
		(18 "In8.Cu" signal "L9GND")
		(20 "In9.Cu" signal "L10")
		(22 "In10.Cu" signal "L11GND")
		(24 "In11.Cu" signal "L12")
		(26 "In12.Cu" signal "L13GND")
		(2 "B.Cu" signal "BOTTOM")
		(9 "F.Adhes" user "F.Adhesive")
		(11 "B.Adhes" user "B.Adhesive")
		(13 "F.Paste" user "Package Geometry/Pastemask Top")
		(15 "B.Paste" user "Package Geometry/Pastemask Bottom")
		(5 "F.SilkS" user "Ref Des/Silkscreen Top")
		(7 "B.SilkS" user "Ref Des/Silkscreen Bottom")
		(1 "F.Mask" user "Board Geometry/Soldermask Top")
		(3 "B.Mask" user "Board Geometry/Soldermask Bottom")
		(17 "Dwgs.User" user "User.Drawings")
		(19 "Cmts.User" user "User.Comments")
		(21 "Eco1.User" user "User.Eco1")
		(23 "Eco2.User" user "User.Eco2")
		(25 "Edge.Cuts" user "Board Geometry/Outline")
		(27 "Margin" user)
		(31 "F.CrtYd" user "Package Geometry/Place Bound Top")
		(29 "B.CrtYd" user "Package Geometry/Place Bound Bottom")
		(35 "F.Fab" user "Ref Des/Assembly Top")
		(33 "B.Fab" user "Ref Des/Assembly Bottom")
	)
	(footprint ""
		(layer "B.Cu")
		(at 442.3918 -141.062202 90)
		(property "Reference" "C25W91"
			(at 0.8382 -0.67818 90)
			(unlocked yes)
			(layer "B.SilkS")
			(effects
				(font
					(size 0.4064 0.254)
					(thickness 0.1524)
				)
				(justify left mirror)
			)
		)
		(property "Value" ""
			(at 0 0 90)
			(layer "B.Fab")
			(effects
				(font
					(size 1.27 1.27)
				)
				(justify mirror)
			)
		)
		(duplicate_pad_numbers_are_jumpers no)
		(fp_poly
			(pts
				(xy -0.3048 -0.1016) (xy -0.3048 0.9906) (xy 0.3048 0.9906) (xy 0.3048 -0.1016)
			)
			(stroke
				(width 0)
				(type default)
			)
			(fill no)
			(layer "B.CrtYd")
		)
		(fp_line
			(start 0.3048 -0.1016)
			(end 0.3048 0.9906)
			(stroke
				(width 0.1)
				(type default)
			)
			(layer "B.Fab")
		)
		(fp_line
			(start -0.3048 -0.1016)
			(end 0.3048 -0.1016)
			(stroke
				(width 0.1)
				(type default)
			)
			(layer "B.Fab")
		)
		(fp_line
			(start 0.3048 0.9906)
			(end -0.3048 0.9906)
			(stroke
				(width 0.1)
				(type default)
			)
			(layer "B.Fab")
		)
		(fp_line
			(start -0.3048 0.9906)
			(end -0.3048 -0.1016)
			(stroke
				(width 0.1)
				(type default)
			)
			(layer "B.Fab")
		)
		(pad "1" smd rect
			(at 0 0 270)
			(size 0.508 0.508)
			(layers "B.Cu" "B.Mask" "B.Paste")
			(net "P3V3_STBY")
		)
		(pad "2" smd rect
			(at 0 0.889 270)
			(size 0.508 0.508)
			(layers "B.Cu" "B.Mask" "B.Paste")
			(net "GND")
		)
		(zone
			(layer "B.Cu")
			(hatch none 0.5)
			(connect_pads
				(clearance 0)
			)
			(min_thickness 0.25)
			(keepout
				(tracks allowed)
				(vias not_allowed)
				(pads allowed)
				(copperpour not_allowed)
				(footprints allowed)
			)
			(placement
				(enabled no)
				(sheetname "")
			)
			(fill
				(thermal_gap 0.5)
				(thermal_bridge_width 0.5)
				(island_removal_mode 0)
			)
			(polygon
				(pts
					(xy 442.6458 -141.316202) (xy 442.6458 -140.808202) (xy 443.0268 -140.808202) (xy 443.0268 -141.316202)
				)
			)
		)
		(zone
			(layer "B.Cu")
			(hatch none 0.5)
			(connect_pads
				(clearance 0)
			)
			(min_thickness 0.25)
			(keepout
				(tracks not_allowed)
				(vias allowed)
				(pads allowed)
				(copperpour not_allowed)
				(footprints allowed)
			)
			(placement
				(enabled no)
				(sheetname "")
			)
			(fill
				(thermal_gap 0.5)
				(thermal_bridge_width 0.5)
				(island_removal_mode 0)
			)
			(polygon
				(pts
					(xy 443.0268 -141.316202) (xy 443.0268 -140.808202) (xy 442.6458 -140.808202) (xy 442.6458 -141.316202)
				)
			)
		)
	)
	(footprint ""
		(layer "B.Cu")
		(at 454.2282 -52.330858)
		(property "Reference" "C1R7"
			(at 0 0 0)
			(layer "B.SilkS")
			(hide yes)
			(effects
				(font
					(size 1.27 1.27)
				)
				(justify mirror)
			)
		)
		(property "Value" ""
			(at 0 0 0)
			(layer "B.Fab")
			(effects
				(font
					(size 1.27 1.27)
				)
				(justify mirror)
			)
		)
		(duplicate_pad_numbers_are_jumpers no)
		(fp_poly
			(pts
				(xy -0.3048 -0.1016) (xy -0.3048 0.9906) (xy 0.3048 0.9906) (xy 0.3048 -0.1016)
			)
			(stroke
				(width 0)
				(type default)
			)
			(fill no)
			(layer "B.CrtYd")
		)
		(fp_line
			(start -0.3048 -0.1016)
			(end 0.3048 -0.1016)
			(stroke
				(width 0.1)
				(type default)
			)
			(layer "B.Fab")
		)
		(fp_line
			(start -0.3048 0.9906)
			(end -0.3048 -0.1016)
			(stroke
				(width 0.1)
				(type default)
			)
			(layer "B.Fab")
		)
		(fp_line
			(start 0.3048 -0.1016)
			(end 0.3048 0.9906)
			(stroke
				(width 0.1)
				(type default)
			)
			(layer "B.Fab")
		)
		(fp_line
			(start 0.3048 0.9906)
			(end -0.3048 0.9906)
			(stroke
				(width 0.1)
				(type default)
			)
			(layer "B.Fab")
		)
		(pad "1" smd rect
			(at 0 0 180)
			(size 0.508 0.508)
			(layers "B.Cu" "B.Mask" "B.Paste")
			(net "P3E_CPU0_PE3_OCP_TXN<3>")
		)
		(pad "2" smd rect
			(at 0 0.889 180)
			(size 0.508 0.508)
			(layers "B.Cu" "B.Mask" "B.Paste")
			(net "P3E_OCP_CPU0_PE3_C_TXN<3>")
		)
		(zone
			(layer "B.Cu")
			(hatch none 0.5)
			(connect_pads
				(clearance 0)
			)
			(min_thickness 0.25)
			(keepout
				(tracks allowed)
				(vias not_allowed)
				(pads allowed)
				(copperpour not_allowed)
				(footprints allowed)
			)
			(placement
				(enabled no)
				(sheetname "")
			)
			(fill
				(thermal_gap 0.5)
				(thermal_bridge_width 0.5)
				(island_removal_mode 0)
			)
			(polygon
				(pts
					(xy 454.4822 -52.076858) (xy 453.9742 -52.076858) (xy 453.9742 -51.695858) (xy 454.4822 -51.695858)
				)
			)
		)
	)
	(footprint ""
		(layer "B.Cu")
		(at 113.761012 -29.94152 90)
		(property "Reference" "SH7U2"
			(at 0 0 90)
			(layer "B.SilkS")
			(hide yes)
			(effects
				(font
					(size 1.27 1.27)
				)
				(justify mirror)
			)
		)
		(property "Value" ""
			(at 0 0 90)
			(layer "B.Fab")
			(effects
				(font
					(size 1.27 1.27)
				)
				(justify mirror)
			)
		)
		(duplicate_pad_numbers_are_jumpers no)
		(fp_poly
			(pts
				(xy 0.1651 -0.0508) (xy 0.1651 0.5842) (xy -0.1651 0.5842) (xy -0.1651 -0.0508)
			)
			(stroke
				(width 0)
				(type default)
			)
			(fill no)
			(layer "B.CrtYd")
		)
		(fp_line
			(start 0.1651 -0.0508)
			(end -0.1651 -0.0508)
			(stroke
				(width 0.1)
				(type default)
			)
			(layer "B.Fab")
		)
		(fp_line
			(start -0.1651 -0.0508)
			(end -0.1651 0.5842)
			(stroke
				(width 0.1)
				(type default)
			)
			(layer "B.Fab")
		)
		(fp_line
			(start 0.1651 0.5842)
			(end 0.1651 -0.0508)
			(stroke
				(width 0.1)
				(type default)
			)
			(layer "B.Fab")
		)
		(fp_line
			(start -0.1651 0.5842)
			(end 0.1651 0.5842)
			(stroke
				(width 0.1)
				(type default)
			)
			(layer "B.Fab")
		)
		(pad "1" smd custom
			(at 0 0 90)
			(size 0.0762 0.0762)
			(layers "B.Cu" "B.Mask" "B.Paste")
			(net "VSENSE_PVDDQ_GHJ_N")
			(options
				(clearance outline)
				(anchor circle)
			)
			(primitives
				(gr_poly
					(pts
						(arc
							(start -0.1524 0.10795)
							(mid -0.098518 0.130268)
							(end -0.0762 0.18415)
						)
						(xy -0.0762 0.22225) (xy 0.0762 0.22225)
						(arc
							(start 0.0762 0.18415)
							(mid 0.098518 0.130268)
							(end 0.1524 0.10795)
						)
						(xy 0.1524 -0.22225) (xy -0.1524 -0.22225)
					)
					(width 0)
					(fill yes)
				)
			)
		)
		(pad "2" smd custom
			(at 0 0.5334 270)
			(size 0.0762 0.0762)
			(layers "B.Cu" "B.Mask" "B.Paste")
			(net "GND")
			(options
				(clearance outline)
				(anchor circle)
			)
			(primitives
				(gr_poly
					(pts
						(arc
							(start -0.1524 0.10795)
							(mid -0.098518 0.130268)
							(end -0.0762 0.18415)
						)
						(xy -0.0762 0.22225) (xy 0.0762 0.22225)
						(arc
							(start 0.0762 0.18415)
							(mid 0.098518 0.130268)
							(end 0.1524 0.10795)
						)
						(xy 0.1524 -0.22225) (xy -0.1524 -0.22225)
					)
					(width 0)
					(fill yes)
				)
			)
		)
	)
	(footprint ""
		(layer "B.Cu")
		(at 116.332 -75.692 90)
		(property "Reference" "R7P14"
			(at 0 0 90)
			(layer "B.SilkS")
			(hide yes)
			(effects
				(font
					(size 1.27 1.27)
				)
				(justify mirror)
			)
		)
		(property "Value" ""
			(at 0 0 90)
			(layer "B.Fab")
			(effects
				(font
					(size 1.27 1.27)
				)
				(justify mirror)
			)
		)
		(duplicate_pad_numbers_are_jumpers no)
		(fp_poly
			(pts
				(xy 0.2794 -0.1016) (xy -0.2794 -0.1016) (xy -0.2794 0.9906) (xy 0.2794 0.9906)
			)
			(stroke
				(width 0)
				(type default)
			)
			(fill no)
			(layer "B.CrtYd")
		)
		(fp_line
			(start 0.2794 -0.1016)
			(end 0.2794 0.9906)
			(stroke
				(width 0.1)
				(type default)
			)
			(layer "B.Fab")
		)
		(fp_line
			(start -0.2794 -0.1016)
			(end 0.2794 -0.1016)
			(stroke
				(width 0.1)
				(type default)
			)
			(layer "B.Fab")
		)
		(fp_line
			(start 0.2794 0.9906)
			(end -0.2794 0.9906)
			(stroke
				(width 0.1)
				(type default)
			)
			(layer "B.Fab")
		)
		(fp_line
			(start -0.2794 0.9906)
			(end -0.2794 -0.1016)
			(stroke
				(width 0.1)
				(type default)
			)
			(layer "B.Fab")
		)
		(pad "1" smd rect
			(at 0 0 270)
			(size 0.508 0.508)
			(layers "B.Cu" "B.Mask" "B.Paste")
			(net "GND")
		)
		(pad "2" smd rect
			(at 0 0.889 270)
			(size 0.508 0.508)
			(layers "B.Cu" "B.Mask" "B.Paste")
			(net "PD_CPU1_DMIMODE_OVERRIDE")
		)
		(zone
			(layer "B.Cu")
			(hatch none 0.5)
			(connect_pads
				(clearance 0)
			)
			(min_thickness 0.25)
			(keepout
				(tracks allowed)
				(vias not_allowed)
				(pads allowed)
				(copperpour not_allowed)
				(footprints allowed)
			)
			(placement
				(enabled no)
				(sheetname "")
			)
			(fill
				(thermal_gap 0.5)
				(thermal_bridge_width 0.5)
				(island_removal_mode 0)
			)
			(polygon
				(pts
					(xy 116.586 -75.946) (xy 116.586 -75.438) (xy 116.967 -75.438) (xy 116.967 -75.946)
				)
			)
		)
		(zone
			(layer "B.Cu")
			(hatch none 0.5)
			(connect_pads
				(clearance 0)
			)
			(min_thickness 0.25)
			(keepout
				(tracks not_allowed)
				(vias allowed)
				(pads allowed)
				(copperpour not_allowed)
				(footprints allowed)
			)
			(placement
				(enabled no)
				(sheetname "")
			)
			(fill
				(thermal_gap 0.5)
				(thermal_bridge_width 0.5)
				(island_removal_mode 0)
			)
			(polygon
				(pts
					(xy 116.967 -75.946) (xy 116.967 -75.438) (xy 116.586 -75.438) (xy 116.586 -75.946)
				)
			)
		)
	)
	(footprint ""
		(layer "B.Cu")
		(at 271.350486 -73.51014)
		(property "Reference" "C5P30"
			(at 0 0 0)
			(layer "B.SilkS")
			(hide yes)
			(effects
				(font
					(size 1.27 1.27)
				)
				(justify mirror)
			)
		)
		(property "Value" ""
			(at 0 0 0)
			(layer "B.Fab")
			(effects
				(font
					(size 1.27 1.27)
				)
				(justify mirror)
			)
		)
		(duplicate_pad_numbers_are_jumpers no)
		(fp_poly
			(pts
				(xy 0.7239 -0.2159) (xy -0.7239 -0.2159) (xy -0.7239 1.9939) (xy 0.7239 1.9939)
			)
			(stroke
				(width 0)
				(type default)
			)
			(fill no)
			(layer "B.CrtYd")
		)
		(fp_line
			(start -0.7239 -0.2159)
			(end 0.7239 -0.2159)
			(stroke
				(width 0.1)
				(type default)
			)
			(layer "B.Fab")
		)
		(fp_line
			(start -0.7239 1.9939)
			(end -0.7239 -0.2159)
			(stroke
				(width 0.1)
				(type default)
			)
			(layer "B.Fab")
		)
		(fp_line
			(start 0.7239 -0.2159)
			(end 0.7239 1.9939)
			(stroke
				(width 0.1)
				(type default)
			)
			(layer "B.Fab")
		)
		(fp_line
			(start 0.7239 1.9939)
			(end -0.7239 1.9939)
			(stroke
				(width 0.1)
				(type default)
			)
			(layer "B.Fab")
		)
		(pad "1" smd rect
			(at 0 0 180)
			(size 1.27 1.016)
			(layers "B.Cu" "B.Mask" "B.Paste")
			(net "PVCCMCP_CPU0")
		)
		(pad "2" smd rect
			(at 0 1.778 180)
			(size 1.27 1.016)
			(layers "B.Cu" "B.Mask" "B.Paste")
			(net "GND")
		)
		(zone
			(layer "B.Cu")
			(hatch none 0.5)
			(connect_pads
				(clearance 0)
			)
			(min_thickness 0.25)
			(keepout
				(tracks not_allowed)
				(vias allowed)
				(pads allowed)
				(copperpour not_allowed)
				(footprints allowed)
			)
			(placement
				(enabled no)
				(sheetname "")
			)
			(fill
				(thermal_gap 0.5)
				(thermal_bridge_width 0.5)
				(island_removal_mode 0)
			)
			(polygon
				(pts
					(xy 271.985486 -73.00214) (xy 270.715486 -73.00214) (xy 270.715486 -72.24014) (xy 271.985486 -72.24014)
				)
			)
		)
	)
	(footprint ""
		(layer "B.Cu")
		(at 197.866 -97.282 90)
		(property "Reference" "C6N6"
			(at 0 0 90)
			(layer "B.SilkS")
			(hide yes)
			(effects
				(font
					(size 1.27 1.27)
				)
				(justify mirror)
			)
		)
		(property "Value" ""
			(at 0 0 90)
			(layer "B.Fab")
			(effects
				(font
					(size 1.27 1.27)
				)
				(justify mirror)
			)
		)
		(duplicate_pad_numbers_are_jumpers no)
		(fp_rect
			(start -0.7239 -0.2159)
			(end 0.7239 1.9939)
			(stroke
				(width 0)
				(type default)
			)
			(fill no)
			(layer "B.CrtYd")
		)
		(fp_line
			(start 0.7239 -0.2159)
			(end 0.7239 1.9939)
			(stroke
				(width 0.1)
				(type default)
			)
			(layer "B.Fab")
		)
		(fp_line
			(start -0.7239 -0.2159)
			(end 0.7239 -0.2159)
			(stroke
				(width 0.1)
				(type default)
			)
			(layer "B.Fab")
		)
		(fp_line
			(start 0.7239 1.9939)
			(end -0.7239 1.9939)
			(stroke
				(width 0.1)
				(type default)
			)
			(layer "B.Fab")
		)
		(fp_line
			(start -0.7239 1.9939)
			(end -0.7239 -0.2159)
			(stroke
				(width 0.1)
				(type default)
			)
			(layer "B.Fab")
		)
		(pad "1" smd rect
			(at 0 0 270)
			(size 1.27 1.016)
			(layers "B.Cu" "B.Mask" "B.Paste")
			(net "VR_FET_SW_P12V_STBY_PVCCIN_CPU0")
		)
		(pad "2" smd rect
			(at 0 1.778 270)
			(size 1.27 1.016)
			(layers "B.Cu" "B.Mask" "B.Paste")
			(net "GND")
		)
		(zone
			(layer "B.Cu")
			(hatch none 0.5)
			(connect_pads
				(clearance 0)
			)
			(min_thickness 0.25)
			(keepout
				(tracks not_allowed)
				(vias allowed)
				(pads allowed)
				(copperpour not_allowed)
				(footprints allowed)
			)
			(placement
				(enabled no)
				(sheetname "")
			)
			(fill
				(thermal_gap 0.5)
				(thermal_bridge_width 0.5)
				(island_removal_mode 0)
			)
			(polygon
				(pts
					(xy 198.374 -96.647) (xy 199.136 -96.647) (xy 199.136 -97.917) (xy 198.374 -97.917)
				)
			)
		)
	)
	(footprint ""
		(layer "B.Cu")
		(at 422.574974 -40.982646 180)
		(property "Reference" "C25W57"
			(at 0.8382 -0.67818 180)
			(unlocked yes)
			(layer "B.SilkS")
			(effects
				(font
					(size 0.4064 0.254)
					(thickness 0.1524)
				)
				(justify left mirror)
			)
		)
		(property "Value" ""
			(at 0 0 0)
			(layer "B.Fab")
			(effects
				(font
					(size 1.27 1.27)
				)
				(justify mirror)
			)
		)
		(duplicate_pad_numbers_are_jumpers no)
		(fp_poly
			(pts
				(xy -0.3048 -0.1016) (xy -0.3048 0.9906) (xy 0.3048 0.9906) (xy 0.3048 -0.1016)
			)
			(stroke
				(width 0)
				(type default)
			)
			(fill no)
			(layer "B.CrtYd")
		)
		(fp_line
			(start 0.3048 0.9906)
			(end -0.3048 0.9906)
			(stroke
				(width 0.1)
				(type default)
			)
			(layer "B.Fab")
		)
		(fp_line
			(start 0.3048 -0.1016)
			(end 0.3048 0.9906)
			(stroke
				(width 0.1)
				(type default)
			)
			(layer "B.Fab")
		)
		(fp_line
			(start -0.3048 0.9906)
			(end -0.3048 -0.1016)
			(stroke
				(width 0.1)
				(type default)
			)
			(layer "B.Fab")
		)
		(fp_line
			(start -0.3048 -0.1016)
			(end 0.3048 -0.1016)
			(stroke
				(width 0.1)
				(type default)
			)
			(layer "B.Fab")
		)
		(pad "1" smd rect
			(at 0 0)
			(size 0.508 0.508)
			(layers "B.Cu" "B.Mask" "B.Paste")
			(net "VCC_PA_3V3")
		)
		(pad "2" smd rect
			(at 0 0.889)
			(size 0.508 0.508)
			(layers "B.Cu" "B.Mask" "B.Paste")
			(net "GND")
		)
		(zone
			(layer "B.Cu")
			(hatch none 0.5)
			(connect_pads
				(clearance 0)
			)
			(min_thickness 0.25)
			(keepout
				(tracks not_allowed)
				(vias allowed)
				(pads allowed)
				(copperpour not_allowed)
				(footprints allowed)
			)
			(placement
				(enabled no)
				(sheetname "")
			)
			(fill
				(thermal_gap 0.5)
				(thermal_bridge_width 0.5)
				(island_removal_mode 0)
			)
			(polygon
				(pts
					(xy 422.320974 -41.617646) (xy 422.828974 -41.617646) (xy 422.828974 -41.236646) (xy 422.320974 -41.236646)
				)
			)
		)
		(zone
			(layer "B.Cu")
			(hatch none 0.5)
			(connect_pads
				(clearance 0)
			)
			(min_thickness 0.25)
			(keepout
				(tracks allowed)
				(vias not_allowed)
				(pads allowed)
				(copperpour not_allowed)
				(footprints allowed)
			)
			(placement
				(enabled no)
				(sheetname "")
			)
			(fill
				(thermal_gap 0.5)
				(thermal_bridge_width 0.5)
				(island_removal_mode 0)
			)
			(polygon
				(pts
					(xy 422.320974 -41.236646) (xy 422.828974 -41.236646) (xy 422.828974 -41.617646) (xy 422.320974 -41.617646)
				)
			)
		)
	)
	(footprint ""
		(layer "B.Cu")
		(at 88.392 -3.3528 90)
		(property "Reference" "C5G85"
			(at -1.14681 0.76708 180)
			(unlocked yes)
			(layer "B.SilkS")
			(effects
				(font
					(size 0.7874 0.5842)
					(thickness 0.1524)
				)
				(justify mirror)
			)
		)
		(property "Value" ""
			(at 0 0 90)
			(layer "B.Fab")
			(effects
				(font
					(size 1.27 1.27)
				)
				(justify mirror)
			)
		)
		(duplicate_pad_numbers_are_jumpers no)
		(fp_rect
			(start -0.4953 -0.2032)
			(end 0.4953 1.6002)
			(stroke
				(width 0)
				(type default)
			)
			(fill no)
			(layer "B.CrtYd")
		)
		(fp_line
			(start 0.4953 -0.2032)
			(end -0.4953 -0.2032)
			(stroke
				(width 0.1)
				(type default)
			)
			(layer "B.Fab")
		)
		(fp_line
			(start -0.4953 -0.2032)
			(end -0.4953 1.6002)
			(stroke
				(width 0.1)
				(type default)
			)
			(layer "B.Fab")
		)
		(fp_line
			(start 0.4953 1.6002)
			(end 0.4953 -0.2032)
			(stroke
				(width 0.1)
				(type default)
			)
			(layer "B.Fab")
		)
		(fp_line
			(start -0.4953 1.6002)
			(end 0.4953 1.6002)
			(stroke
				(width 0.1)
				(type default)
			)
			(layer "B.Fab")
		)
		(pad "1" smd rect
			(at 0 0 270)
			(size 0.762 0.889)
			(layers "B.Cu" "B.Mask" "B.Paste")
			(net "PVDDQ_GHJ")
		)
		(pad "2" smd rect
			(at 0 1.397 270)
			(size 0.762 0.889)
			(layers "B.Cu" "B.Mask" "B.Paste")
			(net "GND")
		)
		(zone
			(layer "B.Cu")
			(hatch none 0.5)
			(connect_pads
				(clearance 0)
			)
			(min_thickness 0.25)
			(keepout
				(tracks not_allowed)
				(vias allowed)
				(pads allowed)
				(copperpour not_allowed)
				(footprints allowed)
			)
			(placement
				(enabled no)
				(sheetname "")
			)
			(fill
				(thermal_gap 0.5)
				(thermal_bridge_width 0.5)
				(island_removal_mode 0)
			)
			(polygon
				(pts
					(xy 88.8365 -2.9718) (xy 89.3445 -2.9718) (xy 89.3445 -3.7338) (xy 88.8365 -3.7338)
				)
			)
		)
	)
)
